(kicad_pcb
	(version 20260206)
	(generator "pcbnew")
	(generator_version "10.0")
	(general
		(thickness 1.6)
		(legacy_teardrops no)
	)
	(paper "A4")
	(title_block
		(title "Bryce Canyon_F.DPB_16315-1-OCP.brd")
		(comment 1 "Bryce Canyon / footprints 2077-2078 of 2223")
	)
	(layers
		(0 "F.Cu" signal "TOP")
		(4 "In1.Cu" signal "L2GND")
		(6 "In2.Cu" signal "L3")
		(8 "In3.Cu" signal "L4GND")
		(10 "In4.Cu" signal "L5")
		(12 "In5.Cu" signal "L6VCC")
		(14 "In6.Cu" signal "L7VCC")
		(16 "In7.Cu" signal "L8")
		(18 "In8.Cu" signal "L9GND")
		(20 "In9.Cu" signal "L10")
		(22 "In10.Cu" signal "L11GND")
		(2 "B.Cu" signal "BOTTOM")
		(9 "F.Adhes" user "F.Adhesive")
		(11 "B.Adhes" user "B.Adhesive")
		(13 "F.Paste" user "Package Geometry/Pastemask Top")
		(15 "B.Paste" user "Package Geometry/Pastemask Bottom")
		(5 "F.SilkS" user "Ref Des/Silkscreen Top")
		(7 "B.SilkS" user "Ref Des/Silkscreen Bottom")
		(1 "F.Mask" user "Board Geometry/Soldermask Top")
		(3 "B.Mask" user "Board Geometry/Soldermask Bottom")
		(17 "Dwgs.User" user "User.Drawings")
		(19 "Cmts.User" user "User.Comments")
		(21 "Eco1.User" user "User.Eco1")
		(23 "Eco2.User" user "User.Eco2")
		(25 "Edge.Cuts" user "Board Geometry/Outline")
		(27 "Margin" user)
		(31 "F.CrtYd" user "Package Geometry/Place Bound Top")
		(29 "B.CrtYd" user "Package Geometry/Place Bound Bottom")
		(35 "F.Fab" user "Ref Des/Assembly Top")
		(33 "B.Fab" user "Ref Des/Assembly Bottom")
	)
	(footprint ""
		(layer "B.Cu")
		(at 434.750972 -252.076966 180)
		(property "Reference" "C636"
			(at 0 0 0)
			(layer "B.SilkS")
			(hide yes)
			(effects
				(font
					(size 1.27 1.27)
				)
				(justify mirror)
			)
		)
		(property "Value" "SC10U16V5KX-7-GP-U"
			(at 0.0762 -6.1214 180)
			(unlocked yes)
			(layer "B.Fab")
			(hide yes)
			(effects
				(font
					(size 1.016 1.016)
					(thickness 0.1524)
				)
				(justify mirror)
			)
		)
		(property "Device Type" "C805H58"
			(at 0.0762 -8.1534 180)
			(unlocked yes)
			(layer "B.Fab")
			(hide yes)
			(effects
				(font
					(size 1.016 1.016)
					(thickness 0.1524)
				)
				(justify mirror)
			)
		)
		(duplicate_pad_numbers_are_jumpers no)
		(fp_line
			(start -0.635 0)
			(end 0.635 0)
			(stroke
				(width 0.508)
				(type default)
			)
			(layer "B.SilkS")
		)
		(fp_rect
			(start 0.9652 1.778)
			(end -0.9652 -1.778)
			(stroke
				(width 0)
				(type default)
			)
			(fill no)
			(layer "B.CrtYd")
		)
		(fp_poly
			(pts
				(xy 0.9652 -1.778) (xy -0.9652 -1.778) (xy -0.9652 1.778) (xy 0.9652 1.778)
			)
			(stroke
				(width 0)
				(type default)
			)
			(fill no)
			(layer "B.Fab")
		)
		(pad "1" smd rect
			(at 0 -0.9652)
			(size 1.397 1.143)
			(layers "B.Cu" "B.Mask" "B.Paste")
			(net "P12V_A_VIN_U22")
		)
		(pad "2" smd rect
			(at 0 0.9652)
			(size 1.397 1.143)
			(layers "B.Cu" "B.Mask" "B.Paste")
			(net "GND")
		)
	)
	(footprint ""
		(layer "B.Cu")
		(at 456.5396 -248.9454 90)
		(property "Reference" "L6"
			(at 0 0 90)
			(layer "B.SilkS")
			(hide yes)
			(effects
				(font
					(size 1.27 1.27)
				)
				(justify mirror)
			)
		)
		(property "Value" "IND-1UH-191-GP"
			(at 6.7818 -2.1082 90)
			(unlocked yes)
			(layer "B.Fab")
			(hide yes)
			(effects
				(font
					(size 1.016 1.016)
					(thickness 0.1524)
				)
				(justify mirror)
			)
		)
		(property "Device Type" "L109100-2430-UH119"
			(at 6.7818 -3.6322 90)
			(unlocked yes)
			(layer "B.Fab")
			(hide yes)
			(effects
				(font
					(size 1.016 1.016)
					(thickness 0.1524)
				)
				(justify mirror)
			)
		)
		(duplicate_pad_numbers_are_jumpers no)
		(fp_line
			(start 5.2578 -6.4262)
			(end -5.2578 -6.4262)
			(stroke
				(width 0.1524)
				(type default)
			)
			(layer "B.SilkS")
		)
		(fp_line
			(start -5.2578 -6.4262)
			(end -5.2578 6.4262)
			(stroke
				(width 0.1524)
				(type default)
			)
			(layer "B.SilkS")
		)
		(fp_line
			(start 5.2578 6.4262)
			(end 5.2578 -6.4262)
			(stroke
				(width 0.1524)
				(type default)
			)
			(layer "B.SilkS")
		)
		(fp_line
			(start -5.2578 6.4262)
			(end 5.2578 6.4262)
			(stroke
				(width 0.1524)
				(type default)
			)
			(layer "B.SilkS")
		)
		(fp_rect
			(start 5.0038 5.4229)
			(end -5.0038 -5.4229)
			(stroke
				(width 0)
				(type default)
			)
			(fill no)
			(layer "B.CrtYd")
		)
		(fp_poly
			(pts
				(xy 5.5118 6.5024) (xy 5.5118 -6.5024) (xy -5.5118 -6.5024) (xy -5.5118 -0.8509) (xy -5.0038 -0.8509)
				(xy -5.0038 -5.4229) (xy 5.0038 -5.4229) (xy 5.0038 5.4229) (xy -5.0038 5.4229) (xy -5.0038 -0.8382)
				(xy -5.5118 -0.8382) (xy -5.5118 6.5024)
			)
			(stroke
				(width 0)
				(type default)
			)
			(fill no)
			(layer "B.CrtYd")
		)
		(fp_rect
			(start 5.5118 6.5024)
			(end -5.5118 -6.5024)
			(stroke
				(width 0)
				(type default)
			)
			(fill no)
			(layer "B.Fab")
		)
		(pad "1" smd rect
			(at 0 -4.396994 270)
			(size 3.5052 3.556)
			(layers "B.Cu" "B.Mask" "B.Paste")
			(net "P5V_C_LL")
		)
		(pad "2" smd rect
			(at 0 4.396994 270)
			(size 3.5052 3.556)
			(layers "B.Cu" "B.Mask" "B.Paste")
			(net "P5V_A_3")
		)
	)
)
